# T6G (Grand Teton) — schematic netlist excerpt (pin names and nets, part order shuffled) for the footprints in the layout excerpt that follows; sources: Cadence DE-HDL packaged netlist, KiCad conversion of 04192023_DAF0TMB3IC0_F0TG_MB_C_brd_V02_OCP.brd

R6290  Q_RES  0 5% CHIP  pkg 0402LF  page 179 : A = USB_HUB2_TI_GANGED_MRP_I2C_SLV_CFG0 ; B = USB_HUB2_TI_GANGED
C369  Q_CAP  22UF 4V 20% X6S  pkg C0402  page 345 : A = P1V8_CPU1_RT2_1A ; B = GND

(kicad_pcb
	(version 20260206)
	(generator "pcbnew")
	(generator_version "10.0")
	(general
		(thickness 1.6)
		(legacy_teardrops no)
	)
	(paper "A4")
	(title_block
		(title "04192023_DAF0TMB3IC0_F0TG_MB_C_brd_V02_OCP.brd")
		(comment 1 "Grand Teton / footprints 2707-2708 of 8354")
	)
	(layers
		(0 "F.Cu" signal "TOP")
		(4 "In1.Cu" signal "GND")
		(6 "In2.Cu" signal "IN1")
		(8 "In3.Cu" signal "GND1")
		(10 "In4.Cu" signal "IN2")
		(12 "In5.Cu" signal "GND2")
		(14 "In6.Cu" signal "IN3")
		(16 "In7.Cu" signal "GND3")
		(18 "In8.Cu" signal "VCC")
		(20 "In9.Cu" signal "VCC1")
		(22 "In10.Cu" signal "GND4")
		(24 "In11.Cu" signal "IN4")
		(26 "In12.Cu" signal "GND5")
		(28 "In13.Cu" signal "IN5")
		(30 "In14.Cu" signal "GND6")
		(32 "In15.Cu" signal "IN6")
		(34 "In16.Cu" signal "GND7")
		(2 "B.Cu" signal "BOTTOM")
		(9 "F.Adhes" user "F.Adhesive")
		(11 "B.Adhes" user "B.Adhesive")
		(13 "F.Paste" user "Package Geometry/Pastemask Top")
		(15 "B.Paste" user "Package Geometry/Pastemask Bottom")
		(5 "F.SilkS" user "Ref Des/Silkscreen Top")
		(7 "B.SilkS" user "Ref Des/Silkscreen Bottom")
		(1 "F.Mask" user "Board Geometry/Soldermask Top")
		(3 "B.Mask" user "Board Geometry/Soldermask Bottom")
		(17 "Dwgs.User" user "User.Drawings")
		(19 "Cmts.User" user "User.Comments")
		(21 "Eco1.User" user "User.Eco1")
		(23 "Eco2.User" user "User.Eco2")
		(25 "Edge.Cuts" user "Board Geometry/Outline")
		(27 "Margin" user)
		(31 "F.CrtYd" user "Package Geometry/Place Bound Top")
		(29 "B.CrtYd" user "Package Geometry/Place Bound Bottom")
		(35 "F.Fab" user "Ref Des/Assembly Top")
		(33 "B.Fab" user "Ref Des/Assembly Bottom")
	)
	(footprint ""
		(layer "F.Cu")
		(at 110.235238 -39.40175 90)
		(property "Reference" "R6290"
			(at 0 0 90)
			(layer "F.SilkS")
			(hide yes)
			(effects
				(font
					(size 1.27 1.27)
				)
			)
		)
		(property "Value" ""
			(at 0 0 90)
			(layer "F.Fab")
			(effects
				(font
					(size 1.27 1.27)
				)
			)
		)
		(duplicate_pad_numbers_are_jumpers no)
		(fp_line
			(start 0.7874 -0.4064)
			(end 0.7874 0.4064)
			(stroke
				(width 0.1524)
				(type default)
			)
			(layer "F.SilkS")
		)
		(fp_line
			(start -0.7874 -0.4064)
			(end 0.7874 -0.4064)
			(stroke
				(width 0.1524)
				(type default)
			)
			(layer "F.SilkS")
		)
		(fp_line
			(start 0.7874 0.4064)
			(end -0.7874 0.4064)
			(stroke
				(width 0.1524)
				(type default)
			)
			(layer "F.SilkS")
		)
		(fp_line
			(start -0.7874 0.4064)
			(end -0.7874 -0.4064)
			(stroke
				(width 0.1524)
				(type default)
			)
			(layer "F.SilkS")
		)
		(fp_line
			(start -0.12065 -0.305054)
			(end -0.12065 -0.2794)
			(stroke
				(width 0.1)
				(type default)
			)
			(layer "F.Fab")
		)
		(fp_line
			(start -0.67945 -0.305054)
			(end -0.12065 -0.305054)
			(stroke
				(width 0.1)
				(type default)
			)
			(layer "F.Fab")
		)
		(fp_line
			(start 0.67945 -0.3048)
			(end 0.67945 0.3048)
			(stroke
				(width 0.1)
				(type default)
			)
			(layer "F.Fab")
		)
		(fp_line
			(start 0.12065 -0.3048)
			(end 0.67945 -0.3048)
			(stroke
				(width 0.1)
				(type default)
			)
			(layer "F.Fab")
		)
		(fp_line
			(start 0.12065 -0.2794)
			(end 0.12065 -0.3048)
			(stroke
				(width 0.1)
				(type default)
			)
			(layer "F.Fab")
		)
		(fp_line
			(start -0.12065 -0.2794)
			(end 0.12065 -0.2794)
			(stroke
				(width 0.1)
				(type default)
			)
			(layer "F.Fab")
		)
		(fp_line
			(start 0.120396 0.2794)
			(end -0.12065 0.2794)
			(stroke
				(width 0.1)
				(type default)
			)
			(layer "F.Fab")
		)
		(fp_line
			(start -0.12065 0.2794)
			(end -0.12065 0.3048)
			(stroke
				(width 0.1)
				(type default)
			)
			(layer "F.Fab")
		)
		(fp_line
			(start 0.67945 0.3048)
			(end 0.120396 0.3048)
			(stroke
				(width 0.1)
				(type default)
			)
			(layer "F.Fab")
		)
		(fp_line
			(start 0.120396 0.3048)
			(end 0.120396 0.2794)
			(stroke
				(width 0.1)
				(type default)
			)
			(layer "F.Fab")
		)
		(fp_line
			(start -0.12065 0.3048)
			(end -0.67945 0.3048)
			(stroke
				(width 0.1)
				(type default)
			)
			(layer "F.Fab")
		)
		(fp_line
			(start -0.67945 0.3048)
			(end -0.67945 -0.305054)
			(stroke
				(width 0.1)
				(type default)
			)
			(layer "F.Fab")
		)
		(pad "1" smd circle
			(at -0.40005 0 90)
			(size 0 0)
			(layers "F.Cu" "F.Mask" "F.Paste")
			(net "USB_HUB2_TI_GANGED_MRP_I2C_SLV_CFG0")
		)
		(pad "2" smd circle
			(at 0.40005 0 90)
			(size 0 0)
			(layers "F.Cu" "F.Mask" "F.Paste")
			(net "USB_HUB2_TI_GANGED")
		)
	)
	(footprint ""
		(layer "F.Cu")
		(at 169.121328 -388.366 90)
		(property "Reference" "C369"
			(at 0 0 90)
			(layer "F.SilkS")
			(hide yes)
			(effects
				(font
					(size 1.27 1.27)
				)
			)
		)
		(property "Value" ""
			(at 0 0 90)
			(layer "F.Fab")
			(effects
				(font
					(size 1.27 1.27)
				)
			)
		)
		(duplicate_pad_numbers_are_jumpers no)
		(fp_line
			(start 0.7874 -0.4064)
			(end 0.7874 0.4064)
			(stroke
				(width 0.1524)
				(type default)
			)
			(layer "F.SilkS")
		)
		(fp_line
			(start -0.7874 -0.4064)
			(end 0.7874 -0.4064)
			(stroke
				(width 0.1524)
				(type default)
			)
			(layer "F.SilkS")
		)
		(fp_line
			(start 0.7874 0.4064)
			(end -0.7874 0.4064)
			(stroke
				(width 0.1524)
				(type default)
			)
			(layer "F.SilkS")
		)
		(fp_line
			(start -0.7874 0.4064)
			(end -0.7874 -0.4064)
			(stroke
				(width 0.1524)
				(type default)
			)
			(layer "F.SilkS")
		)
		(fp_line
			(start -0.12065 -0.305054)
			(end -0.12065 -0.2794)
			(stroke
				(width 0.1)
				(type default)
			)
			(layer "F.Fab")
		)
		(fp_line
			(start -0.67945 -0.305054)
			(end -0.12065 -0.305054)
			(stroke
				(width 0.1)
				(type default)
			)
			(layer "F.Fab")
		)
		(fp_line
			(start 0.67945 -0.3048)
			(end 0.67945 0.3048)
			(stroke
				(width 0.1)
				(type default)
			)
			(layer "F.Fab")
		)
		(fp_line
			(start 0.12065 -0.3048)
			(end 0.67945 -0.3048)
			(stroke
				(width 0.1)
				(type default)
			)
			(layer "F.Fab")
		)
		(fp_line
			(start 0.12065 -0.2794)
			(end 0.12065 -0.3048)
			(stroke
				(width 0.1)
				(type default)
			)
			(layer "F.Fab")
		)
		(fp_line
			(start -0.12065 -0.2794)
			(end 0.12065 -0.2794)
			(stroke
				(width 0.1)
				(type default)
			)
			(layer "F.Fab")
		)
		(fp_line
			(start 0.120396 0.2794)
			(end -0.12065 0.2794)
			(stroke
				(width 0.1)
				(type default)
			)
			(layer "F.Fab")
		)
		(fp_line
			(start -0.12065 0.2794)
			(end -0.12065 0.3048)
			(stroke
				(width 0.1)
				(type default)
			)
			(layer "F.Fab")
		)
		(fp_line
			(start 0.67945 0.3048)
			(end 0.120396 0.3048)
			(stroke
				(width 0.1)
				(type default)
			)
			(layer "F.Fab")
		)
		(fp_line
			(start 0.120396 0.3048)
			(end 0.120396 0.2794)
			(stroke
				(width 0.1)
				(type default)
			)
			(layer "F.Fab")
		)
		(fp_line
			(start -0.12065 0.3048)
			(end -0.67945 0.3048)
			(stroke
				(width 0.1)
				(type default)
			)
			(layer "F.Fab")
		)
		(fp_line
			(start -0.67945 0.3048)
			(end -0.67945 -0.305054)
			(stroke
				(width 0.1)
				(type default)
			)
			(layer "F.Fab")
		)
		(pad "1" smd circle
			(at -0.40005 0 90)
			(size 0 0)
			(layers "F.Cu" "F.Mask" "F.Paste")
			(net "P1V8_CPU1_RT2_1A")
		)
		(pad "2" smd circle
			(at 0.40005 0 90)
			(size 0 0)
			(layers "F.Cu" "F.Mask" "F.Paste")
			(net "GND")
		)
	)
)
